# T6G (Grand Teton) — schematic netlist excerpt (pin names and nets, part order shuffled) for the footprints in the layout excerpt that follows; sources: Cadence DE-HDL packaged netlist, KiCad conversion of 04192023_DAF0TMB3IC0_F0TG_MB_C_brd_V02_OCP.brd

C240  Q_CAP  100UF 4V 20% X6S  pkg C0805  page 323 : A = P0V9_CPU1_RT0_2A ; B = GND
PR488  Q_RES  1.5 1% EMPTY  pkg 0402LF  page 222 : A = SW_PVDDIO_P1_SW1_RC ; B = GND
R3468  Q_RES  49.9 1% CHIP  pkg 0402LF  page 128 : A = RST_PERST_1_SWB_BUF_R_N ; B = RST_PERST_1_SWB_BUF_N

(kicad_pcb
	(version 20260206)
	(generator "pcbnew")
	(generator_version "10.0")
	(general
		(thickness 1.6)
		(legacy_teardrops no)
	)
	(paper "A4")
	(title_block
		(title "04192023_DAF0TMB3IC0_F0TG_MB_C_brd_V02_OCP.brd")
		(comment 1 "Grand Teton / footprints 1020-1022 of 8354")
	)
	(layers
		(0 "F.Cu" signal "TOP")
		(4 "In1.Cu" signal "GND")
		(6 "In2.Cu" signal "IN1")
		(8 "In3.Cu" signal "GND1")
		(10 "In4.Cu" signal "IN2")
		(12 "In5.Cu" signal "GND2")
		(14 "In6.Cu" signal "IN3")
		(16 "In7.Cu" signal "GND3")
		(18 "In8.Cu" signal "VCC")
		(20 "In9.Cu" signal "VCC1")
		(22 "In10.Cu" signal "GND4")
		(24 "In11.Cu" signal "IN4")
		(26 "In12.Cu" signal "GND5")
		(28 "In13.Cu" signal "IN5")
		(30 "In14.Cu" signal "GND6")
		(32 "In15.Cu" signal "IN6")
		(34 "In16.Cu" signal "GND7")
		(2 "B.Cu" signal "BOTTOM")
		(9 "F.Adhes" user "F.Adhesive")
		(11 "B.Adhes" user "B.Adhesive")
		(13 "F.Paste" user "Package Geometry/Pastemask Top")
		(15 "B.Paste" user "Package Geometry/Pastemask Bottom")
		(5 "F.SilkS" user "Ref Des/Silkscreen Top")
		(7 "B.SilkS" user "Ref Des/Silkscreen Bottom")
		(1 "F.Mask" user "Board Geometry/Soldermask Top")
		(3 "B.Mask" user "Board Geometry/Soldermask Bottom")
		(17 "Dwgs.User" user "User.Drawings")
		(19 "Cmts.User" user "User.Comments")
		(21 "Eco1.User" user "User.Eco1")
		(23 "Eco2.User" user "User.Eco2")
		(25 "Edge.Cuts" user "Board Geometry/Outline")
		(27 "Margin" user)
		(31 "F.CrtYd" user "Package Geometry/Place Bound Top")
		(29 "B.CrtYd" user "Package Geometry/Place Bound Bottom")
		(35 "F.Fab" user "Ref Des/Assembly Top")
		(33 "B.Fab" user "Ref Des/Assembly Bottom")
	)
	(footprint ""
		(layer "F.Cu")
		(at 49.866296 -344.986864 90)
		(property "Reference" "PR488"
			(at 0 0 90)
			(layer "F.SilkS")
			(hide yes)
			(effects
				(font
					(size 1.27 1.27)
				)
			)
		)
		(property "Value" ""
			(at 0 0 90)
			(layer "F.Fab")
			(effects
				(font
					(size 1.27 1.27)
				)
			)
		)
		(duplicate_pad_numbers_are_jumpers no)
		(fp_line
			(start 0.7874 -0.4064)
			(end 0.7874 0.4064)
			(stroke
				(width 0.1524)
				(type default)
			)
			(layer "F.SilkS")
		)
		(fp_line
			(start -0.7874 -0.4064)
			(end 0.7874 -0.4064)
			(stroke
				(width 0.1524)
				(type default)
			)
			(layer "F.SilkS")
		)
		(fp_line
			(start 0.7874 0.4064)
			(end -0.7874 0.4064)
			(stroke
				(width 0.1524)
				(type default)
			)
			(layer "F.SilkS")
		)
		(fp_line
			(start -0.7874 0.4064)
			(end -0.7874 -0.4064)
			(stroke
				(width 0.1524)
				(type default)
			)
			(layer "F.SilkS")
		)
		(fp_line
			(start -0.12065 -0.305054)
			(end -0.12065 -0.2794)
			(stroke
				(width 0.1)
				(type default)
			)
			(layer "F.Fab")
		)
		(fp_line
			(start -0.67945 -0.305054)
			(end -0.12065 -0.305054)
			(stroke
				(width 0.1)
				(type default)
			)
			(layer "F.Fab")
		)
		(fp_line
			(start 0.67945 -0.3048)
			(end 0.67945 0.3048)
			(stroke
				(width 0.1)
				(type default)
			)
			(layer "F.Fab")
		)
		(fp_line
			(start 0.12065 -0.3048)
			(end 0.67945 -0.3048)
			(stroke
				(width 0.1)
				(type default)
			)
			(layer "F.Fab")
		)
		(fp_line
			(start 0.12065 -0.2794)
			(end 0.12065 -0.3048)
			(stroke
				(width 0.1)
				(type default)
			)
			(layer "F.Fab")
		)
		(fp_line
			(start -0.12065 -0.2794)
			(end 0.12065 -0.2794)
			(stroke
				(width 0.1)
				(type default)
			)
			(layer "F.Fab")
		)
		(fp_line
			(start 0.120396 0.2794)
			(end -0.12065 0.2794)
			(stroke
				(width 0.1)
				(type default)
			)
			(layer "F.Fab")
		)
		(fp_line
			(start -0.12065 0.2794)
			(end -0.12065 0.3048)
			(stroke
				(width 0.1)
				(type default)
			)
			(layer "F.Fab")
		)
		(fp_line
			(start 0.67945 0.3048)
			(end 0.120396 0.3048)
			(stroke
				(width 0.1)
				(type default)
			)
			(layer "F.Fab")
		)
		(fp_line
			(start 0.120396 0.3048)
			(end 0.120396 0.2794)
			(stroke
				(width 0.1)
				(type default)
			)
			(layer "F.Fab")
		)
		(fp_line
			(start -0.12065 0.3048)
			(end -0.67945 0.3048)
			(stroke
				(width 0.1)
				(type default)
			)
			(layer "F.Fab")
		)
		(fp_line
			(start -0.67945 0.3048)
			(end -0.67945 -0.305054)
			(stroke
				(width 0.1)
				(type default)
			)
			(layer "F.Fab")
		)
		(pad "1" smd circle
			(at -0.40005 0 90)
			(size 0 0)
			(layers "F.Cu" "F.Mask" "F.Paste")
			(net "SW_PVDDIO_P1_SW1_RC")
		)
		(pad "2" smd circle
			(at 0.40005 0 90)
			(size 0 0)
			(layers "F.Cu" "F.Mask" "F.Paste")
			(net "GND")
		)
	)
	(footprint ""
		(layer "F.Cu")
		(at 47.861982 -397.751808)
		(property "Reference" "C240"
			(at 0 0 0)
			(layer "F.SilkS")
			(hide yes)
			(effects
				(font
					(size 1.27 1.27)
				)
			)
		)
		(property "Value" ""
			(at 0 0 0)
			(layer "F.Fab")
			(effects
				(font
					(size 1.27 1.27)
				)
			)
		)
		(duplicate_pad_numbers_are_jumpers no)
		(fp_line
			(start -1.524 -0.762)
			(end 1.524 -0.762)
			(stroke
				(width 0.1524)
				(type default)
			)
			(layer "F.SilkS")
		)
		(fp_line
			(start -1.524 0.762)
			(end -1.524 -0.762)
			(stroke
				(width 0.1524)
				(type default)
			)
			(layer "F.SilkS")
		)
		(fp_line
			(start 1.524 -0.762)
			(end 1.524 0.762)
			(stroke
				(width 0.1524)
				(type default)
			)
			(layer "F.SilkS")
		)
		(fp_line
			(start 1.524 0.762)
			(end -1.524 0.762)
			(stroke
				(width 0.1524)
				(type default)
			)
			(layer "F.SilkS")
		)
		(fp_line
			(start -1.1049 -0.724916)
			(end -1.1049 0.724916)
			(stroke
				(width 0.1)
				(type default)
			)
			(layer "F.Fab")
		)
		(fp_line
			(start -1.1049 0.724916)
			(end 1.1049 0.724916)
			(stroke
				(width 0.1)
				(type default)
			)
			(layer "F.Fab")
		)
		(fp_line
			(start 1.1049 -0.724916)
			(end -1.1049 -0.724916)
			(stroke
				(width 0.1)
				(type default)
			)
			(layer "F.Fab")
		)
		(fp_line
			(start 1.1049 0.724916)
			(end 1.1049 -0.724916)
			(stroke
				(width 0.1)
				(type default)
			)
			(layer "F.Fab")
		)
		(pad "1" smd rect
			(at -0.889 0 180)
			(size 1.016 1.27)
			(layers "F.Cu" "F.Mask" "F.Paste")
			(net "P0V9_CPU1_RT0_2A")
		)
		(pad "2" smd rect
			(at 0.889 0 180)
			(size 1.016 1.27)
			(layers "F.Cu" "F.Mask" "F.Paste")
			(net "GND")
		)
	)
	(footprint ""
		(layer "F.Cu")
		(at 41.73601 -438.531)
		(property "Reference" "R3468"
			(at 0 0 0)
			(layer "F.SilkS")
			(hide yes)
			(effects
				(font
					(size 1.27 1.27)
				)
			)
		)
		(property "Value" ""
			(at 0 0 0)
			(layer "F.Fab")
			(effects
				(font
					(size 1.27 1.27)
				)
			)
		)
		(duplicate_pad_numbers_are_jumpers no)
		(fp_line
			(start -0.7874 -0.4064)
			(end 0.7874 -0.4064)
			(stroke
				(width 0.1524)
				(type default)
			)
			(layer "F.SilkS")
		)
		(fp_line
			(start -0.7874 0.4064)
			(end -0.7874 -0.4064)
			(stroke
				(width 0.1524)
				(type default)
			)
			(layer "F.SilkS")
		)
		(fp_line
			(start 0.7874 -0.4064)
			(end 0.7874 0.4064)
			(stroke
				(width 0.1524)
				(type default)
			)
			(layer "F.SilkS")
		)
		(fp_line
			(start 0.7874 0.4064)
			(end -0.7874 0.4064)
			(stroke
				(width 0.1524)
				(type default)
			)
			(layer "F.SilkS")
		)
		(fp_line
			(start -0.67945 -0.305054)
			(end -0.12065 -0.305054)
			(stroke
				(width 0.1)
				(type default)
			)
			(layer "F.Fab")
		)
		(fp_line
			(start -0.67945 0.3048)
			(end -0.67945 -0.305054)
			(stroke
				(width 0.1)
				(type default)
			)
			(layer "F.Fab")
		)
		(fp_line
			(start -0.12065 -0.305054)
			(end -0.12065 -0.2794)
			(stroke
				(width 0.1)
				(type default)
			)
			(layer "F.Fab")
		)
		(fp_line
			(start -0.12065 -0.2794)
			(end 0.12065 -0.2794)
			(stroke
				(width 0.1)
				(type default)
			)
			(layer "F.Fab")
		)
		(fp_line
			(start -0.12065 0.2794)
			(end -0.12065 0.3048)
			(stroke
				(width 0.1)
				(type default)
			)
			(layer "F.Fab")
		)
		(fp_line
			(start -0.12065 0.3048)
			(end -0.67945 0.3048)
			(stroke
				(width 0.1)
				(type default)
			)
			(layer "F.Fab")
		)
		(fp_line
			(start 0.120396 0.2794)
			(end -0.12065 0.2794)
			(stroke
				(width 0.1)
				(type default)
			)
			(layer "F.Fab")
		)
		(fp_line
			(start 0.120396 0.3048)
			(end 0.120396 0.2794)
			(stroke
				(width 0.1)
				(type default)
			)
			(layer "F.Fab")
		)
		(fp_line
			(start 0.12065 -0.3048)
			(end 0.67945 -0.3048)
			(stroke
				(width 0.1)
				(type default)
			)
			(layer "F.Fab")
		)
		(fp_line
			(start 0.12065 -0.2794)
			(end 0.12065 -0.3048)
			(stroke
				(width 0.1)
				(type default)
			)
			(layer "F.Fab")
		)
		(fp_line
			(start 0.67945 -0.3048)
			(end 0.67945 0.3048)
			(stroke
				(width 0.1)
				(type default)
			)
			(layer "F.Fab")
		)
		(fp_line
			(start 0.67945 0.3048)
			(end 0.120396 0.3048)
			(stroke
				(width 0.1)
				(type default)
			)
			(layer "F.Fab")
		)
		(pad "1" smd circle
			(at -0.40005 0)
			(size 0 0)
			(layers "F.Cu" "F.Mask" "F.Paste")
			(net "RST_PERST_1_SWB_BUF_R_N")
		)
		(pad "2" smd circle
			(at 0.40005 0)
			(size 0 0)
			(layers "F.Cu" "F.Mask" "F.Paste")
			(net "RST_PERST_1_SWB_BUF_N")
		)
	)
)
